(kicad_pcb
	(version 20260206)
	(generator "pcbnew")
	(generator_version "10.0")
	(general
		(thickness 1.6)
		(legacy_teardrops no)
	)
	(paper "A4")
	(title_block
		(title "04192023_DAF0TMB3IC0_F0TG_MB_C_brd_V02_OCP.brd")
		(comment 1 "Grand Teton / footprints 3439-3443 of 8354")
	)
	(layers
		(0 "F.Cu" signal "TOP")
		(4 "In1.Cu" signal "GND")
		(6 "In2.Cu" signal "IN1")
		(8 "In3.Cu" signal "GND1")
		(10 "In4.Cu" signal "IN2")
		(12 "In5.Cu" signal "GND2")
		(14 "In6.Cu" signal "IN3")
		(16 "In7.Cu" signal "GND3")
		(18 "In8.Cu" signal "VCC")
		(20 "In9.Cu" signal "VCC1")
		(22 "In10.Cu" signal "GND4")
		(24 "In11.Cu" signal "IN4")
		(26 "In12.Cu" signal "GND5")
		(28 "In13.Cu" signal "IN5")
		(30 "In14.Cu" signal "GND6")
		(32 "In15.Cu" signal "IN6")
		(34 "In16.Cu" signal "GND7")
		(2 "B.Cu" signal "BOTTOM")
		(9 "F.Adhes" user "F.Adhesive")
		(11 "B.Adhes" user "B.Adhesive")
		(13 "F.Paste" user "Package Geometry/Pastemask Top")
		(15 "B.Paste" user "Package Geometry/Pastemask Bottom")
		(5 "F.SilkS" user "Ref Des/Silkscreen Top")
		(7 "B.SilkS" user "Ref Des/Silkscreen Bottom")
		(1 "F.Mask" user "Board Geometry/Soldermask Top")
		(3 "B.Mask" user "Board Geometry/Soldermask Bottom")
		(17 "Dwgs.User" user "User.Drawings")
		(19 "Cmts.User" user "User.Comments")
		(21 "Eco1.User" user "User.Eco1")
		(23 "Eco2.User" user "User.Eco2")
		(25 "Edge.Cuts" user "Board Geometry/Outline")
		(27 "Margin" user)
		(31 "F.CrtYd" user "Package Geometry/Place Bound Top")
		(29 "B.CrtYd" user "Package Geometry/Place Bound Bottom")
		(35 "F.Fab" user "Ref Des/Assembly Top")
		(33 "B.Fab" user "Ref Des/Assembly Bottom")
	)
	(footprint ""
		(layer "F.Cu")
		(at 105.222548 -385.5212 90)
		(property "Reference" "R745"
			(at 0 0 90)
			(layer "F.SilkS")
			(hide yes)
			(effects
				(font
					(size 1.27 1.27)
				)
			)
		)
		(property "Value" ""
			(at 0 0 90)
			(layer "F.Fab")
			(effects
				(font
					(size 1.27 1.27)
				)
			)
		)
		(duplicate_pad_numbers_are_jumpers no)
		(fp_line
			(start 0.32512 -0.175006)
			(end 0.32512 0.175006)
			(stroke
				(width 0.1)
				(type default)
			)
			(layer "F.Fab")
		)
		(fp_line
			(start -0.32512 -0.175006)
			(end 0.32512 -0.175006)
			(stroke
				(width 0.1)
				(type default)
			)
			(layer "F.Fab")
		)
		(fp_line
			(start 0.32512 0.175006)
			(end -0.32512 0.175006)
			(stroke
				(width 0.1)
				(type default)
			)
			(layer "F.Fab")
		)
		(fp_line
			(start -0.32512 0.175006)
			(end -0.32512 -0.175006)
			(stroke
				(width 0.1)
				(type default)
			)
			(layer "F.Fab")
		)
		(pad "1" smd rect
			(at -0.2667 0 90)
			(size 0.3048 0.381)
			(layers "F.Cu" "F.Mask" "F.Paste")
			(net "P1V8_CPU1_RT_1D")
		)
		(pad "2" smd rect
			(at 0.2667 0 270)
			(size 0.3048 0.381)
			(layers "F.Cu" "F.Mask" "F.Paste")
			(net "RT_CPU1_P1_ADDR2")
		)
	)
	(footprint ""
		(layer "F.Cu")
		(at 409.450794 -142.009368 180)
		(property "Reference" "PR8089"
			(at 0 0 180)
			(layer "F.SilkS")
			(hide yes)
			(effects
				(font
					(size 1.27 1.27)
				)
			)
		)
		(property "Value" ""
			(at 0 0 180)
			(layer "F.Fab")
			(effects
				(font
					(size 1.27 1.27)
				)
			)
		)
		(duplicate_pad_numbers_are_jumpers no)
		(fp_line
			(start 0.7874 0.4064)
			(end -0.7874 0.4064)
			(stroke
				(width 0.1524)
				(type default)
			)
			(layer "F.SilkS")
		)
		(fp_line
			(start 0.7874 -0.4064)
			(end 0.7874 0.4064)
			(stroke
				(width 0.1524)
				(type default)
			)
			(layer "F.SilkS")
		)
		(fp_line
			(start -0.7874 0.4064)
			(end -0.7874 -0.4064)
			(stroke
				(width 0.1524)
				(type default)
			)
			(layer "F.SilkS")
		)
		(fp_line
			(start -0.7874 -0.4064)
			(end 0.7874 -0.4064)
			(stroke
				(width 0.1524)
				(type default)
			)
			(layer "F.SilkS")
		)
		(fp_line
			(start 0.67945 0.3048)
			(end 0.120396 0.3048)
			(stroke
				(width 0.1)
				(type default)
			)
			(layer "F.Fab")
		)
		(fp_line
			(start 0.67945 -0.3048)
			(end 0.67945 0.3048)
			(stroke
				(width 0.1)
				(type default)
			)
			(layer "F.Fab")
		)
		(fp_line
			(start 0.12065 -0.2794)
			(end 0.12065 -0.3048)
			(stroke
				(width 0.1)
				(type default)
			)
			(layer "F.Fab")
		)
		(fp_line
			(start 0.12065 -0.3048)
			(end 0.67945 -0.3048)
			(stroke
				(width 0.1)
				(type default)
			)
			(layer "F.Fab")
		)
		(fp_line
			(start 0.120396 0.3048)
			(end 0.120396 0.2794)
			(stroke
				(width 0.1)
				(type default)
			)
			(layer "F.Fab")
		)
		(fp_line
			(start 0.120396 0.2794)
			(end -0.12065 0.2794)
			(stroke
				(width 0.1)
				(type default)
			)
			(layer "F.Fab")
		)
		(fp_line
			(start -0.12065 0.3048)
			(end -0.67945 0.3048)
			(stroke
				(width 0.1)
				(type default)
			)
			(layer "F.Fab")
		)
		(fp_line
			(start -0.12065 0.2794)
			(end -0.12065 0.3048)
			(stroke
				(width 0.1)
				(type default)
			)
			(layer "F.Fab")
		)
		(fp_line
			(start -0.12065 -0.2794)
			(end 0.12065 -0.2794)
			(stroke
				(width 0.1)
				(type default)
			)
			(layer "F.Fab")
		)
		(fp_line
			(start -0.12065 -0.305054)
			(end -0.12065 -0.2794)
			(stroke
				(width 0.1)
				(type default)
			)
			(layer "F.Fab")
		)
		(fp_line
			(start -0.67945 0.3048)
			(end -0.67945 -0.305054)
			(stroke
				(width 0.1)
				(type default)
			)
			(layer "F.Fab")
		)
		(fp_line
			(start -0.67945 -0.305054)
			(end -0.12065 -0.305054)
			(stroke
				(width 0.1)
				(type default)
			)
			(layer "F.Fab")
		)
		(pad "1" smd circle
			(at -0.40005 0 180)
			(size 0 0)
			(layers "F.Cu" "F.Mask" "F.Paste")
			(net "P5V_AUX_CS")
		)
		(pad "2" smd circle
			(at 0.40005 0 180)
			(size 0 0)
			(layers "F.Cu" "F.Mask" "F.Paste")
			(net "GND")
		)
	)
	(footprint ""
		(layer "F.Cu")
		(at 423.64406 -342.281764 -90)
		(property "Reference" "PL23"
			(at -2.142236 4.77139 90)
			(unlocked yes)
			(layer "F.SilkS")
			(effects
				(font
					(size 0.7874 0.5842)
					(thickness 0.1524)
				)
				(justify left)
			)
		)
		(property "Value" ""
			(at 0 0 270)
			(layer "F.Fab")
			(effects
				(font
					(size 1.27 1.27)
				)
			)
		)
		(duplicate_pad_numbers_are_jumpers no)
		(fp_line
			(start -4.99999 3.849878)
			(end -4.99999 2.23901)
			(stroke
				(width 0.1524)
				(type default)
			)
			(layer "F.SilkS")
		)
		(fp_line
			(start 4.99999 3.849878)
			(end -4.99999 3.849878)
			(stroke
				(width 0.1524)
				(type default)
			)
			(layer "F.SilkS")
		)
		(fp_line
			(start 4.99999 2.23901)
			(end 4.99999 3.849878)
			(stroke
				(width 0.1524)
				(type default)
			)
			(layer "F.SilkS")
		)
		(fp_line
			(start -4.99999 -2.23901)
			(end -4.99999 -3.849878)
			(stroke
				(width 0.1524)
				(type default)
			)
			(layer "F.SilkS")
		)
		(fp_line
			(start -4.99999 -3.849878)
			(end 4.99999 -3.849878)
			(stroke
				(width 0.1524)
				(type default)
			)
			(layer "F.SilkS")
		)
		(fp_line
			(start 4.99999 -3.849878)
			(end 4.99999 -2.23901)
			(stroke
				(width 0.1524)
				(type default)
			)
			(layer "F.SilkS")
		)
		(fp_line
			(start -4.99999 3.849878)
			(end -4.99999 -3.849878)
			(stroke
				(width 0.1)
				(type default)
			)
			(layer "F.Fab")
		)
		(fp_line
			(start 4.99999 3.849878)
			(end -4.99999 3.849878)
			(stroke
				(width 0.1)
				(type default)
			)
			(layer "F.Fab")
		)
		(fp_line
			(start -4.99999 -3.849878)
			(end 4.99999 -3.849878)
			(stroke
				(width 0.1)
				(type default)
			)
			(layer "F.Fab")
		)
		(fp_line
			(start 4.99999 -3.849878)
			(end 4.99999 3.849878)
			(stroke
				(width 0.1)
				(type default)
			)
			(layer "F.Fab")
		)
		(pad "1" smd rect
			(at -3.299968 0 270)
			(size 3.302 4.2164)
			(layers "F.Cu" "F.Mask" "F.Paste")
			(net "SW_PVDD11_S3_P0_SW1")
		)
		(pad "2" smd rect
			(at 3.299968 0 270)
			(size 3.302 4.2164)
			(layers "F.Cu" "F.Mask" "F.Paste")
			(net "PVDD11_S3_P0")
		)
	)
	(footprint ""
		(layer "F.Cu")
		(at 120.396 -423.672 180)
		(property "Reference" "R3390"
			(at 0 0 180)
			(layer "F.SilkS")
			(hide yes)
			(effects
				(font
					(size 1.27 1.27)
				)
			)
		)
		(property "Value" ""
			(at 0 0 180)
			(layer "F.Fab")
			(effects
				(font
					(size 1.27 1.27)
				)
			)
		)
		(duplicate_pad_numbers_are_jumpers no)
		(fp_line
			(start 0.7874 0.4064)
			(end -0.7874 0.4064)
			(stroke
				(width 0.1524)
				(type default)
			)
			(layer "F.SilkS")
		)
		(fp_line
			(start 0.7874 -0.4064)
			(end 0.7874 0.4064)
			(stroke
				(width 0.1524)
				(type default)
			)
			(layer "F.SilkS")
		)
		(fp_line
			(start -0.7874 0.4064)
			(end -0.7874 -0.4064)
			(stroke
				(width 0.1524)
				(type default)
			)
			(layer "F.SilkS")
		)
		(fp_line
			(start -0.7874 -0.4064)
			(end 0.7874 -0.4064)
			(stroke
				(width 0.1524)
				(type default)
			)
			(layer "F.SilkS")
		)
		(fp_line
			(start 0.67945 0.3048)
			(end 0.120396 0.3048)
			(stroke
				(width 0.1)
				(type default)
			)
			(layer "F.Fab")
		)
		(fp_line
			(start 0.67945 -0.3048)
			(end 0.67945 0.3048)
			(stroke
				(width 0.1)
				(type default)
			)
			(layer "F.Fab")
		)
		(fp_line
			(start 0.12065 -0.2794)
			(end 0.12065 -0.3048)
			(stroke
				(width 0.1)
				(type default)
			)
			(layer "F.Fab")
		)
		(fp_line
			(start 0.12065 -0.3048)
			(end 0.67945 -0.3048)
			(stroke
				(width 0.1)
				(type default)
			)
			(layer "F.Fab")
		)
		(fp_line
			(start 0.120396 0.3048)
			(end 0.120396 0.2794)
			(stroke
				(width 0.1)
				(type default)
			)
			(layer "F.Fab")
		)
		(fp_line
			(start 0.120396 0.2794)
			(end -0.12065 0.2794)
			(stroke
				(width 0.1)
				(type default)
			)
			(layer "F.Fab")
		)
		(fp_line
			(start -0.12065 0.3048)
			(end -0.67945 0.3048)
			(stroke
				(width 0.1)
				(type default)
			)
			(layer "F.Fab")
		)
		(fp_line
			(start -0.12065 0.2794)
			(end -0.12065 0.3048)
			(stroke
				(width 0.1)
				(type default)
			)
			(layer "F.Fab")
		)
		(fp_line
			(start -0.12065 -0.2794)
			(end 0.12065 -0.2794)
			(stroke
				(width 0.1)
				(type default)
			)
			(layer "F.Fab")
		)
		(fp_line
			(start -0.12065 -0.305054)
			(end -0.12065 -0.2794)
			(stroke
				(width 0.1)
				(type default)
			)
			(layer "F.Fab")
		)
		(fp_line
			(start -0.67945 0.3048)
			(end -0.67945 -0.305054)
			(stroke
				(width 0.1)
				(type default)
			)
			(layer "F.Fab")
		)
		(fp_line
			(start -0.67945 -0.305054)
			(end -0.12065 -0.305054)
			(stroke
				(width 0.1)
				(type default)
			)
			(layer "F.Fab")
		)
		(pad "1" smd circle
			(at -0.40005 0 180)
			(size 0 0)
			(layers "F.Cu" "F.Mask" "F.Paste")
			(net "GPU_FPGA_BOOT_EN_BUF_R")
		)
		(pad "2" smd circle
			(at 0.40005 0 180)
			(size 0 0)
			(layers "F.Cu" "F.Mask" "F.Paste")
			(net "GPU_FPGA_BOOT_EN_BUF")
		)
	)
	(footprint ""
		(layer "F.Cu")
		(at 77.215746 -395.436852 -90)
		(property "Reference" "R758"
			(at 0 0 270)
			(layer "F.SilkS")
			(hide yes)
			(effects
				(font
					(size 1.27 1.27)
				)
			)
		)
		(property "Value" ""
			(at 0 0 270)
			(layer "F.Fab")
			(effects
				(font
					(size 1.27 1.27)
				)
			)
		)
		(duplicate_pad_numbers_are_jumpers no)
		(fp_line
			(start -0.32512 0.175006)
			(end -0.32512 -0.175006)
			(stroke
				(width 0.1)
				(type default)
			)
			(layer "F.Fab")
		)
		(fp_line
			(start 0.32512 0.175006)
			(end -0.32512 0.175006)
			(stroke
				(width 0.1)
				(type default)
			)
			(layer "F.Fab")
		)
		(fp_line
			(start -0.32512 -0.175006)
			(end 0.32512 -0.175006)
			(stroke
				(width 0.1)
				(type default)
			)
			(layer "F.Fab")
		)
		(fp_line
			(start 0.32512 -0.175006)
			(end 0.32512 0.175006)
			(stroke
				(width 0.1)
				(type default)
			)
			(layer "F.Fab")
		)
		(pad "1" smd rect
			(at -0.2667 0 270)
			(size 0.3048 0.381)
			(layers "F.Cu" "F.Mask" "F.Paste")
			(net "P1V8_CPU1_RT_1D")
		)
		(pad "2" smd rect
			(at 0.2667 0 90)
			(size 0.3048 0.381)
			(layers "F.Cu" "F.Mask" "F.Paste")
			(net "RST_RT_CPU1_P1_RESET_R_N")
		)
	)
)
